# SCM (Grand Teton) — schematic netlist excerpt (pin names and nets, part order shuffled) for the footprints in the layout excerpt that follows; sources: Cadence DE-HDL packaged netlist, KiCad conversion of 12092022_DA0F0TMDCD0_F0T_Management_Board_D_brd_V3_OCP.brd

C149  Q_CAP  0.1UF 25V 10% X7R  pkg 0402  page 29 : A = P3V3_AUX ; B = GND
R693  Q_RES  33.2 1% CHIP  pkg 0402LF  page 29 : A = DEBUG_PORT_PRSNT ; B = DEBUG_PORT_PRSNT_R

(kicad_pcb
	(version 20260206)
	(generator "pcbnew")
	(generator_version "10.0")
	(general
		(thickness 1.6)
		(legacy_teardrops no)
	)
	(paper "A4")
	(title_block
		(title "12092022_DA0F0TMDCD0_F0T_Management_Board_D_brd_V3_OCP.brd")
		(comment 1 "Grand Teton / footprints 988-989 of 1440")
	)
	(layers
		(0 "F.Cu" signal "TOP")
		(4 "In1.Cu" signal "GND")
		(6 "In2.Cu" signal "IN1")
		(8 "In3.Cu" signal "GND1")
		(10 "In4.Cu" signal "IN2")
		(12 "In5.Cu" signal "VCC")
		(14 "In6.Cu" signal "VCC1")
		(16 "In7.Cu" signal "IN3")
		(18 "In8.Cu" signal "GND2")
		(20 "In9.Cu" signal "IN4")
		(22 "In10.Cu" signal "GND3")
		(2 "B.Cu" signal "BOTTOM")
		(9 "F.Adhes" user "F.Adhesive")
		(11 "B.Adhes" user "B.Adhesive")
		(13 "F.Paste" user "Package Geometry/Pastemask Top")
		(15 "B.Paste" user "Package Geometry/Pastemask Bottom")
		(5 "F.SilkS" user "Ref Des/Silkscreen Top")
		(7 "B.SilkS" user "Ref Des/Silkscreen Bottom")
		(1 "F.Mask" user "Board Geometry/Soldermask Top")
		(3 "B.Mask" user "Board Geometry/Soldermask Bottom")
		(17 "Dwgs.User" user "User.Drawings")
		(19 "Cmts.User" user "User.Comments")
		(21 "Eco1.User" user "User.Eco1")
		(23 "Eco2.User" user "User.Eco2")
		(25 "Edge.Cuts" user "Board Geometry/Outline")
		(27 "Margin" user)
		(31 "F.CrtYd" user "Package Geometry/Place Bound Top")
		(29 "B.CrtYd" user "Package Geometry/Place Bound Bottom")
		(35 "F.Fab" user "Ref Des/Assembly Top")
		(33 "B.Fab" user "Ref Des/Assembly Bottom")
	)
	(footprint ""
		(layer "B.Cu")
		(at 62.992 -24.257 -90)
		(property "Reference" "C149"
			(at 0 0 90)
			(layer "B.SilkS")
			(hide yes)
			(effects
				(font
					(size 1.27 1.27)
				)
				(justify mirror)
			)
		)
		(property "Value" ""
			(at 0 0 90)
			(layer "B.Fab")
			(effects
				(font
					(size 1.27 1.27)
				)
				(justify mirror)
			)
		)
		(duplicate_pad_numbers_are_jumpers no)
		(fp_line
			(start -0.7874 0.4064)
			(end 0.7874 0.4064)
			(stroke
				(width 0.1524)
				(type default)
			)
			(layer "B.SilkS")
		)
		(fp_line
			(start 0.7874 0.4064)
			(end 0.7874 -0.4064)
			(stroke
				(width 0.1524)
				(type default)
			)
			(layer "B.SilkS")
		)
		(fp_line
			(start -0.7874 -0.4064)
			(end -0.7874 0.4064)
			(stroke
				(width 0.1524)
				(type default)
			)
			(layer "B.SilkS")
		)
		(fp_line
			(start 0.7874 -0.4064)
			(end -0.7874 -0.4064)
			(stroke
				(width 0.1524)
				(type default)
			)
			(layer "B.SilkS")
		)
		(fp_line
			(start -0.67945 0.3048)
			(end -0.120396 0.3048)
			(stroke
				(width 0.1)
				(type default)
			)
			(layer "B.Fab")
		)
		(fp_line
			(start -0.120396 0.3048)
			(end -0.120396 0.2794)
			(stroke
				(width 0.1)
				(type default)
			)
			(layer "B.Fab")
		)
		(fp_line
			(start 0.12065 0.3048)
			(end 0.67945 0.3048)
			(stroke
				(width 0.1)
				(type default)
			)
			(layer "B.Fab")
		)
		(fp_line
			(start 0.67945 0.3048)
			(end 0.67945 -0.305054)
			(stroke
				(width 0.1)
				(type default)
			)
			(layer "B.Fab")
		)
		(fp_line
			(start -0.120396 0.2794)
			(end 0.12065 0.2794)
			(stroke
				(width 0.1)
				(type default)
			)
			(layer "B.Fab")
		)
		(fp_line
			(start 0.12065 0.2794)
			(end 0.12065 0.3048)
			(stroke
				(width 0.1)
				(type default)
			)
			(layer "B.Fab")
		)
		(fp_line
			(start -0.12065 -0.2794)
			(end -0.12065 -0.3048)
			(stroke
				(width 0.1)
				(type default)
			)
			(layer "B.Fab")
		)
		(fp_line
			(start 0.12065 -0.2794)
			(end -0.12065 -0.2794)
			(stroke
				(width 0.1)
				(type default)
			)
			(layer "B.Fab")
		)
		(fp_line
			(start -0.67945 -0.3048)
			(end -0.67945 0.3048)
			(stroke
				(width 0.1)
				(type default)
			)
			(layer "B.Fab")
		)
		(fp_line
			(start -0.12065 -0.3048)
			(end -0.67945 -0.3048)
			(stroke
				(width 0.1)
				(type default)
			)
			(layer "B.Fab")
		)
		(fp_line
			(start 0.12065 -0.305054)
			(end 0.12065 -0.2794)
			(stroke
				(width 0.1)
				(type default)
			)
			(layer "B.Fab")
		)
		(fp_line
			(start 0.67945 -0.305054)
			(end 0.12065 -0.305054)
			(stroke
				(width 0.1)
				(type default)
			)
			(layer "B.Fab")
		)
		(pad "1" smd circle
			(at 0.40005 0 90)
			(size 0 0)
			(layers "B.Cu" "B.Mask" "B.Paste")
			(net "P3V3_AUX")
		)
		(pad "2" smd circle
			(at -0.40005 0 90)
			(size 0 0)
			(layers "B.Cu" "B.Mask" "B.Paste")
			(net "GND")
		)
	)
	(footprint ""
		(layer "B.Cu")
		(at 43.942 -19.431 90)
		(property "Reference" "R693"
			(at 0 0 90)
			(layer "B.SilkS")
			(hide yes)
			(effects
				(font
					(size 1.27 1.27)
				)
				(justify mirror)
			)
		)
		(property "Value" ""
			(at 0 0 90)
			(layer "B.Fab")
			(effects
				(font
					(size 1.27 1.27)
				)
				(justify mirror)
			)
		)
		(duplicate_pad_numbers_are_jumpers no)
		(fp_line
			(start 0.7874 -0.4064)
			(end -0.7874 -0.4064)
			(stroke
				(width 0.1524)
				(type default)
			)
			(layer "B.SilkS")
		)
		(fp_line
			(start -0.7874 -0.4064)
			(end -0.7874 0.4064)
			(stroke
				(width 0.1524)
				(type default)
			)
			(layer "B.SilkS")
		)
		(fp_line
			(start 0.7874 0.4064)
			(end 0.7874 -0.4064)
			(stroke
				(width 0.1524)
				(type default)
			)
			(layer "B.SilkS")
		)
		(fp_line
			(start -0.7874 0.4064)
			(end 0.7874 0.4064)
			(stroke
				(width 0.1524)
				(type default)
			)
			(layer "B.SilkS")
		)
		(fp_line
			(start 0.67945 -0.305054)
			(end 0.12065 -0.305054)
			(stroke
				(width 0.1)
				(type default)
			)
			(layer "B.Fab")
		)
		(fp_line
			(start 0.12065 -0.305054)
			(end 0.12065 -0.2794)
			(stroke
				(width 0.1)
				(type default)
			)
			(layer "B.Fab")
		)
		(fp_line
			(start -0.12065 -0.3048)
			(end -0.67945 -0.3048)
			(stroke
				(width 0.1)
				(type default)
			)
			(layer "B.Fab")
		)
		(fp_line
			(start -0.67945 -0.3048)
			(end -0.67945 0.3048)
			(stroke
				(width 0.1)
				(type default)
			)
			(layer "B.Fab")
		)
		(fp_line
			(start 0.12065 -0.2794)
			(end -0.12065 -0.2794)
			(stroke
				(width 0.1)
				(type default)
			)
			(layer "B.Fab")
		)
		(fp_line
			(start -0.12065 -0.2794)
			(end -0.12065 -0.3048)
			(stroke
				(width 0.1)
				(type default)
			)
			(layer "B.Fab")
		)
		(fp_line
			(start 0.12065 0.2794)
			(end 0.12065 0.3048)
			(stroke
				(width 0.1)
				(type default)
			)
			(layer "B.Fab")
		)
		(fp_line
			(start -0.120396 0.2794)
			(end 0.12065 0.2794)
			(stroke
				(width 0.1)
				(type default)
			)
			(layer "B.Fab")
		)
		(fp_line
			(start 0.67945 0.3048)
			(end 0.67945 -0.305054)
			(stroke
				(width 0.1)
				(type default)
			)
			(layer "B.Fab")
		)
		(fp_line
			(start 0.12065 0.3048)
			(end 0.67945 0.3048)
			(stroke
				(width 0.1)
				(type default)
			)
			(layer "B.Fab")
		)
		(fp_line
			(start -0.120396 0.3048)
			(end -0.120396 0.2794)
			(stroke
				(width 0.1)
				(type default)
			)
			(layer "B.Fab")
		)
		(fp_line
			(start -0.67945 0.3048)
			(end -0.120396 0.3048)
			(stroke
				(width 0.1)
				(type default)
			)
			(layer "B.Fab")
		)
		(pad "1" smd circle
			(at 0.40005 0 270)
			(size 0 0)
			(layers "B.Cu" "B.Mask" "B.Paste")
			(net "DEBUG_PORT_PRSNT")
		)
		(pad "2" smd circle
			(at -0.40005 0 270)
			(size 0 0)
			(layers "B.Cu" "B.Mask" "B.Paste")
			(net "DEBUG_PORT_PRSNT_R")
		)
	)
)
